G04 ================== begin FILE IDENTIFICATION RECORD ==================*
G04 Layout Name:  D:/<user>/Wistron_project/16347-sc/gbr/16347-sc.brd*
G04 Film Name:    P_OUTLINE*
G04 File Format:  Gerber RS274X*
G04 File Origin:  Cadence Allegro 16.5-S056*
G04 Origin Date:  Tue Mar 14 17:08:13 2017*
G04 *
G04 Layer:  BOARD GEOMETRY/PANEL_OUTLINE*
G04 *
G04 Offset:    (0.00 0.00)*
G04 Mirror:    No*
G04 Mode:      Positive*
G04 Rotation:  0*
G04 FullContactRelief:  No*
G04 UndefLineWidth:     6.00*
G04 ================== end FILE IDENTIFICATION RECORD ====================*
%FSLAX35Y35*MOIN*%
%IR0*IPPOS*OFA0.00000B0.00000*MIA0B0*SFA1.00000B1.00000*%
%ADD10C,.006*%
G75*
%LPD*%
G75*
G54D10*
G01X21279Y19685D02*
G03X11201I-5039J0D01*
G01D02*
G03X21279I5039J0D01*
G01X3937Y-3937D02*
X724409D01*
G01X0Y0D02*
G03X3937Y-3937I3937J0D01*
G01X0Y35433D02*
Y0D01*
G01Y51181D02*
G03X3937Y47244I3937J0D01*
G01X0Y51181D02*
Y118898D01*
G01X4724Y47244D02*
X3937D01*
G01X29921Y63780D02*
Y47244D01*
G01X41732Y75591D02*
G03X29921Y63780I0J-11811D01*
G01X4724Y39370D02*
G03Y47244I0J3937D01*
G01X29921D02*
G03Y39370I0J-3937D01*
G01X3937D02*
G03X0Y35433I0J-3937D01*
G01X33858Y39370D02*
X3937D01*
G01X33858D02*
G03X37795Y43307I0J3937D01*
G01Y63780D02*
Y43307D01*
G01X41732Y67717D02*
G03X37795Y63780I0J-3937D01*
G01X65354Y67717D02*
X41732D01*
G01X3937Y122835D02*
G03X0Y118898I0J-3937D01*
G01X60828Y75591D02*
X41732D01*
G01X20531Y99213D02*
G03I-4291J0D01*
G01X29921Y122835D02*
X60828D01*
G01X21279Y154331D02*
G03X11201I-5039J0D01*
G01D02*
G03X21279I5039J0D01*
G01X3937Y130709D02*
X724409D01*
G01X0Y134646D02*
G03X3937Y130709I3937J0D01*
G01X0Y170079D02*
Y134646D01*
G01X4724Y122835D02*
G03Y130709I0J3937D01*
G01X29921D02*
G03Y122835I0J-3937D01*
G01X4724D02*
X3937D01*
G01X0Y185827D02*
G03X3937Y181890I3937J0D01*
G01X0Y185827D02*
Y253544D01*
G01X4724Y181890D02*
X3937D01*
G01X29921Y198426D02*
Y181890D01*
G01X41732Y210237D02*
G03X29921Y198426I0J-11811D01*
G01X60828Y210237D02*
X41732D01*
G01X4724Y174016D02*
G03Y181890I0J3937D01*
G01X29921D02*
G03Y174016I0J-3937D01*
G01X3937D02*
G03X0Y170079I0J-3937D01*
G01X33858Y174016D02*
X3937D01*
G01X33858D02*
G03X37795Y177953I0J3937D01*
G01Y198426D02*
Y177953D01*
G01X41732Y202363D02*
G03X37795Y198426I0J-3937D01*
G01X65354Y202363D02*
X41732D01*
G01X29921Y257481D02*
X60828D01*
G01X3937D02*
G03X0Y253544I0J-3937D01*
G01X4724Y257481D02*
G03Y265355I0J3937D01*
G01X29921D02*
G03Y257481I0J-3937D01*
G01X4724D02*
X3937D01*
G01X20531Y233859D02*
G03I-4291J0D01*
G01X4724Y308662D02*
G03Y316536I0J3937D01*
G01X29921D02*
G03Y308662I0J-3937D01*
G01X21279Y288977D02*
G03X11201I-5039J0D01*
G01D02*
G03X21279I5039J0D01*
G01X3937Y265355D02*
X724409D01*
G01X0Y269292D02*
G03X3937Y265355I3937J0D01*
G01X0Y304725D02*
Y269292D01*
G01X3937Y308662D02*
G03X0Y304725I0J-3937D01*
G01X33858Y308662D02*
X3937D01*
G01X33858D02*
G03X37795Y312599I0J3937D01*
G01X0Y320473D02*
G03X3937Y316536I3937J0D01*
G01X0Y320473D02*
Y388190D01*
G01X4724Y316536D02*
X3937D01*
G01X29921Y333072D02*
Y316536D01*
G01X41732Y344883D02*
G03X29921Y333072I0J-11811D01*
G01X60828Y344883D02*
X41732D01*
G01X37795Y333072D02*
Y312599D01*
G01X41732Y337009D02*
G03X37795Y333072I0J-3937D01*
G01X65354Y337009D02*
X41732D01*
G01X29921Y392127D02*
X60828D01*
G01X3937D02*
G03X0Y388190I0J-3937D01*
G01X4724Y392127D02*
G03Y400001I0J3937D01*
G01X29921D02*
G03Y392127I0J-3937D01*
G01X4724D02*
X3937D01*
G01X20531Y368505D02*
G03I-4291J0D01*
G01X3937Y400001D02*
X724409D01*
G01X0Y403938D02*
G03X3937Y400001I3937J0D01*
G01X0Y439371D02*
Y403938D01*
G01Y455119D02*
G03X3937Y451182I3937J0D01*
G01X4724D02*
X3937D01*
G01X29921Y467718D02*
Y451182D01*
G01X4724Y443308D02*
G03Y451182I0J3937D01*
G01X29921D02*
G03Y443308I0J-3937D01*
G01X21279Y423623D02*
G03X11201I-5039J0D01*
G01D02*
G03X21279I5039J0D01*
G01X3937Y443308D02*
G03X0Y439371I0J-3937D01*
G01X33858Y443308D02*
X3937D01*
G01X33858D02*
G03X37795Y447245I0J3937D01*
G01Y467718D02*
Y447245D01*
G01X0Y455119D02*
Y522836D01*
G01X41732Y479529D02*
G03X29921Y467718I0J-11811D01*
G01X60828Y479529D02*
X41732D01*
G01X20531Y503151D02*
G03I-4291J0D01*
G01X41732Y471655D02*
G03X37795Y467718I0J-3937D01*
G01X65354Y471655D02*
X41732D01*
G01X29921Y526773D02*
X60828D01*
G01X3937D02*
G03X0Y522836I0J-3937D01*
G01X4724Y526773D02*
G03Y534647I0J3937D01*
G01X29921D02*
G03Y526773I0J-3937D01*
G01X4724D02*
X3937D01*
G01Y534647D02*
X724409D01*
G01X0Y538584D02*
G03X3937Y534647I3937J0D01*
G01X0Y574017D02*
Y538584D01*
G01Y589765D02*
G03X3937Y585828I3937J0D01*
G01X0Y589765D02*
Y657482D01*
G01X4724Y585828D02*
X3937D01*
G01X29921Y602364D02*
Y585828D01*
G01X4724Y577954D02*
G03Y585828I0J3937D01*
G01X29921D02*
G03Y577954I0J-3937D01*
G01X21279Y558269D02*
G03X11201I-5039J0D01*
G01D02*
G03X21279I5039J0D01*
G01X3937Y577954D02*
G03X0Y574017I0J-3937D01*
G01X33858Y577954D02*
X3937D01*
G01X33858D02*
G03X37795Y581891I0J3937D01*
G01Y602364D02*
Y581891D01*
G01X41732Y614175D02*
G03X29921Y602364I0J-11811D01*
G01X60828Y614175D02*
X41732D01*
G01X20531Y637797D02*
G03I-4291J0D01*
G01X41732Y606301D02*
G03X37795Y602364I0J-3937D01*
G01X65354Y606301D02*
X41732D01*
G01X29921Y661419D02*
X60828D01*
G01X3937D02*
G03X0Y657482I0J-3937D01*
G01X4724Y661419D02*
G03Y669293I0J3937D01*
G01X29921D02*
G03Y661419I0J-3937D01*
G01X4724D02*
X3937D01*
G01X11201Y692915D02*
G03X21279I5039J0D01*
G01X3937Y669293D02*
X724409D01*
G01X0Y673230D02*
G03X3937Y669293I3937J0D01*
G01X0Y708663D02*
Y673230D01*
G01Y724411D02*
G03X3937Y720474I3937J0D01*
G01X0Y724411D02*
Y792128D01*
G01X4724Y720474D02*
X3937D01*
G01X29921Y737010D02*
Y720474D01*
G01X41732Y748821D02*
G03X29921Y737010I0J-11811D01*
G01X4724Y712600D02*
G03Y720474I0J3937D01*
G01X29921D02*
G03Y712600I0J-3937D01*
G01X21279Y692915D02*
G03X11201I-5039J0D01*
G01X3937Y712600D02*
G03X0Y708663I0J-3937D01*
G01X33858Y712600D02*
X3937D01*
G01X33858D02*
G03X37795Y716537I0J3937D01*
G01Y737010D02*
Y716537D01*
G01X41732Y740947D02*
G03X37795Y737010I0J-3937D01*
G01X60828Y748821D02*
X41732D01*
G01X20531Y772443D02*
G03I-4291J0D01*
G01X65354Y740947D02*
X41732D01*
G01X29921Y796065D02*
X60828D01*
G01X3937D02*
G03X0Y792128I0J-3937D01*
G01X4724Y796065D02*
G03Y803939I0J3937D01*
G01X29921D02*
G03Y796065I0J-3937D01*
G01X4724D02*
X3937D01*
G01X21279Y827561D02*
G03X11201I-5039J0D01*
G01D02*
G03X21279I5039J0D01*
G01X3937Y803939D02*
X724409D01*
G01X0Y807876D02*
G03X3937Y803939I3937J0D01*
G01X0Y843309D02*
Y807876D01*
G01Y859057D02*
G03X3937Y855120I3937J0D01*
G01X0Y859057D02*
Y922837D01*
G01X4724Y855120D02*
X3937D01*
G01X29921Y871656D02*
Y855120D01*
G01X41732Y883467D02*
G03X29921Y871656I0J-11811D01*
G01X4724Y847246D02*
G03Y855120I0J3937D01*
G01X29921D02*
G03Y847246I0J-3937D01*
G01X3937D02*
G03X0Y843309I0J-3937D01*
G01X33858Y847246D02*
X3937D01*
G01X33858D02*
G03X37795Y851183I0J3937D01*
G01Y871656D02*
Y851183D01*
G01X41732Y875593D02*
G03X37795Y871656I0J-3937D01*
G01X65354Y875593D02*
X41732D01*
G01X7874Y930711D02*
G03X0Y922837I0J-7874D01*
G01X60828Y883467D02*
X41732D01*
G01X20531Y907089D02*
G03I-4291J0D01*
G01X60828Y930711D02*
X7874D01*
G01X53445Y19685D02*
G03X42028I-5709J0D01*
G01D02*
G03X53445I5709J0D01*
G01X69291Y63780D02*
G03X65354Y67717I-3937J0D01*
G01X69291Y43307D02*
Y63780D01*
G01Y43307D02*
G03X73228Y39370I3937J0D01*
G01X156102D02*
X73228D01*
G01X64765Y118898D02*
G03X60828Y122835I-3937J0D01*
G01Y75591D02*
G03X64765Y79528I0J3937D01*
G01Y113780D02*
Y118898D01*
G01X72639Y88583D02*
G03X64765I-3937J0D01*
G01Y113780D02*
G03X72639I3937J0D01*
G01X64765Y88583D02*
Y79528D01*
G01X83879Y99213D02*
G03X93879I5000J0D01*
G01D02*
G03X83879I-5000J0D01*
G01X76576Y122835D02*
G03X72639Y118898I0J-3937D01*
G01X76576Y79528D02*
X106694D01*
G01X72639Y83465D02*
G03X76576Y79528I3937J0D01*
G01X72639Y118898D02*
Y83465D01*
G01X53445Y154331D02*
G03X42028I-5709J0D01*
G01D02*
G03X53445I5709J0D01*
G01X797048Y122835D02*
X76576D01*
G01X60828Y210237D02*
G03X64765Y214174I0J3937D01*
G01Y223229D02*
Y214174D01*
G01X76576D02*
X106694D01*
G01X72639Y218111D02*
G03X76576Y214174I3937J0D01*
G01X69291Y198426D02*
G03X65354Y202363I-3937J0D01*
G01X69291Y177953D02*
Y198426D01*
G01Y177953D02*
G03X73228Y174016I3937J0D01*
G01X156102D02*
X73228D01*
G01X64765Y253544D02*
G03X60828Y257481I-3937J0D01*
G01X64765Y248426D02*
Y253544D01*
G01X72639Y223229D02*
G03X64765I-3937J0D01*
G01Y248426D02*
G03X72639I3937J0D01*
G01X83879Y233859D02*
G03X93879I5000J0D01*
G01D02*
G03X83879I-5000J0D01*
G01X76576Y257481D02*
G03X72639Y253544I0J-3937D01*
G01X797048Y257481D02*
X76576D01*
G01X72639Y253544D02*
Y218111D01*
G01X53445Y288977D02*
G03X42028I-5709J0D01*
G01D02*
G03X53445I5709J0D01*
G01X69291Y312599D02*
G03X73228Y308662I3937J0D01*
G01X156102D02*
X73228D01*
G01X60828Y344883D02*
G03X64765Y348820I0J3937D01*
G01X72639Y357875D02*
G03X64765I-3937J0D01*
G01D02*
Y348820D01*
G01X76576D02*
X106694D01*
G01X72639Y352757D02*
G03X76576Y348820I3937J0D01*
G01X72639Y388190D02*
Y352757D01*
G01X69291Y333072D02*
G03X65354Y337009I-3937J0D01*
G01X69291Y312599D02*
Y333072D01*
G01X64765Y388190D02*
G03X60828Y392127I-3937J0D01*
G01X64765Y383072D02*
Y388190D01*
G01Y383072D02*
G03X72639I3937J0D01*
G01X83879Y368505D02*
G03X93879I5000J0D01*
G01D02*
G03X83879I-5000J0D01*
G01X76576Y392127D02*
G03X72639Y388190I0J-3937D01*
G01X797048Y392127D02*
X76576D01*
G01X53445Y423623D02*
G03X42028I-5709J0D01*
G01D02*
G03X53445I5709J0D01*
G01X69291Y447245D02*
Y467718D01*
G01Y447245D02*
G03X73228Y443308I3937J0D01*
G01X156102D02*
X73228D01*
G01X60828Y479529D02*
G03X64765Y483466I0J3937D01*
G01X72639Y492521D02*
G03X64765I-3937J0D01*
G01D02*
Y483466D01*
G01X83879Y503151D02*
G03X93879I5000J0D01*
G01X76576Y483466D02*
X106694D01*
G01X72639Y487403D02*
G03X76576Y483466I3937J0D01*
G01X72639Y522836D02*
Y487403D01*
G01X69291Y467718D02*
G03X65354Y471655I-3937J0D01*
G01X64765Y522836D02*
G03X60828Y526773I-3937J0D01*
G01X64765Y517718D02*
Y522836D01*
G01Y517718D02*
G03X72639I3937J0D01*
G01X93879Y503151D02*
G03X83879I-5000J0D01*
G01X76576Y526773D02*
G03X72639Y522836I0J-3937D01*
G01X797048Y526773D02*
X76576D01*
G01X53445Y558269D02*
G03X42028I-5709J0D01*
G01D02*
G03X53445I5709J0D01*
G01X69291Y581891D02*
Y602364D01*
G01Y581891D02*
G03X73228Y577954I3937J0D01*
G01X156102D02*
X73228D01*
G01X60828Y614175D02*
G03X64765Y618112I0J3937D01*
G01X72639Y627167D02*
G03X64765I-3937J0D01*
G01D02*
Y618112D01*
G01X83879Y637797D02*
G03X93879I5000J0D01*
G01D02*
G03X83879I-5000J0D01*
G01X76576Y618112D02*
X106694D01*
G01X72639Y622049D02*
G03X76576Y618112I3937J0D01*
G01X72639Y657482D02*
Y622049D01*
G01X69291Y602364D02*
G03X65354Y606301I-3937J0D01*
G01X64765Y657482D02*
G03X60828Y661419I-3937J0D01*
G01X64765Y652364D02*
Y657482D01*
G01Y652364D02*
G03X72639I3937J0D01*
G01X42028Y692915D02*
G03X53445I5709J0D01*
G01X76576Y661419D02*
G03X72639Y657482I0J-3937D01*
G01X797048Y661419D02*
X76576D01*
G01X53445Y692915D02*
G03X42028I-5709J0D01*
G01X69291Y737010D02*
G03X65354Y740947I-3937J0D01*
G01X69291Y716537D02*
Y737010D01*
G01Y716538D02*
G03X73228Y712601I3937J0D01*
G01X156102Y712600D02*
X73228D01*
G01X60828Y748821D02*
G03X64765Y752758I0J3937D01*
G01Y787010D02*
Y792128D01*
G01X72639Y761813D02*
G03X64765I-3937J0D01*
G01Y787010D02*
G03X72639I3937J0D01*
G01X64765Y761813D02*
Y752758D01*
G01X83879Y772443D02*
G03X93879I5000J0D01*
G01D02*
G03X83879I-5000J0D01*
G01X76576Y752758D02*
X106694D01*
G01X72639Y756695D02*
G03X76576Y752758I3937J0D01*
G01X72639Y792128D02*
Y756695D01*
G01X64765Y792128D02*
G03X60828Y796065I-3937J0D01*
G01X53445Y827561D02*
G03X42028I-5709J0D01*
G01D02*
G03X53445I5709J0D01*
G01X76576Y796065D02*
G03X72639Y792128I0J-3937D01*
G01X797048Y796065D02*
X76576D01*
G01X69291Y871656D02*
G03X65354Y875593I-3937J0D01*
G01X69291Y851183D02*
Y871656D01*
G01Y851184D02*
G03X73228Y847247I3937J0D01*
G01X156102Y847246D02*
X73228D01*
G01X60828Y883467D02*
G03X64765Y887404I0J3937D01*
G01Y926774D02*
G03X60828Y930711I-3937J0D01*
G01X64765Y921656D02*
Y926774D01*
G01X72639Y896459D02*
G03X64765I-3937J0D01*
G01Y921656D02*
G03X72639I3937J0D01*
G01X64765Y896459D02*
Y887404D01*
G01X83879Y907089D02*
G03X93879I5000J0D01*
G01D02*
G03X83879I-5000J0D01*
G01X76576Y930711D02*
G03X72639Y926774I0J-3937D01*
G01X76576Y887404D02*
X106694D01*
G01X72639Y891341D02*
G03X76576Y887404I3937J0D01*
G01X72639Y926774D02*
Y891341D01*
G01X797048Y930711D02*
X76576D01*
G01X114568Y51181D02*
X138190D01*
G01X110631Y55118D02*
G03X114568Y51181I3937J0D01*
G01X110631Y75591D02*
Y55118D01*
G01X114666Y99213D02*
G03X126083I5708J0D01*
G01D02*
G03X114666I-5709J0D01*
G01X110631Y75591D02*
G03X106694Y79528I-3937J0D01*
G01X114568Y185827D02*
X138190D01*
G01X110631Y189764D02*
G03X114568Y185827I3937J0D01*
G01X110631Y210237D02*
Y189764D01*
G01Y210237D02*
G03X106694Y214174I-3937J0D01*
G01X114666Y233859D02*
G03X126083I5708J0D01*
G01D02*
G03X114666I-5709J0D01*
G01X114568Y320473D02*
X138190D01*
G01X110631Y324410D02*
G03X114568Y320473I3937J0D01*
G01X110631Y344883D02*
Y324410D01*
G01Y344883D02*
G03X106694Y348820I-3937J0D01*
G01X114666Y368505D02*
G03X126083I5708J0D01*
G01D02*
G03X114666I-5709J0D01*
G01Y503151D02*
G03X126083I5708J0D01*
G01X114568Y455119D02*
X138190D01*
G01X110631Y459056D02*
G03X114568Y455119I3937J0D01*
G01X110631Y479529D02*
Y459056D01*
G01Y479529D02*
G03X106694Y483466I-3937J0D01*
G01X126083Y503151D02*
G03X114666I-5709J0D01*
G01X114568Y589765D02*
X138190D01*
G01X110631Y593702D02*
G03X114568Y589765I3937J0D01*
G01X110631Y614175D02*
Y593702D01*
G01X114666Y637797D02*
G03X126083I5708J0D01*
G01D02*
G03X114666I-5709J0D01*
G01X110631Y614175D02*
G03X106694Y618112I-3937J0D01*
G01X114568Y724411D02*
X138190D01*
G01X110631Y728348D02*
G03X114568Y724411I3937J0D01*
G01X110631Y748821D02*
Y728348D01*
G01X114666Y772443D02*
G03X126083I5708J0D01*
G01D02*
G03X114666I-5709J0D01*
G01X110631Y748821D02*
G03X106694Y752758I-3937J0D01*
G01X114568Y859057D02*
X138190D01*
G01X110631Y862994D02*
G03X114568Y859057I3937J0D01*
G01X110631Y883467D02*
Y862994D01*
G01X114666Y907089D02*
G03X126083I5708J0D01*
G01D02*
G03X114666I-5709J0D01*
G01X110631Y883467D02*
G03X106694Y887404I-3937J0D01*
G01X142127Y55118D02*
Y75591D01*
G01X138190Y51181D02*
G03X142127Y55118I0J3937D01*
G01X180905Y71654D02*
G03Y79528I0J3937D01*
G01X156102Y39370D02*
G03X160039Y43307I0J3937D01*
G01Y67717D02*
Y43307D01*
G01X163976Y71654D02*
G03X160039Y67717I0J-3937D01*
G01X223031Y71654D02*
X163976D01*
G01X146064Y79528D02*
X230906D01*
G01X146064D02*
G03X142127Y75591I0J-3937D01*
G01X146064Y214174D02*
X230906D01*
G01X146064D02*
G03X142127Y210237I0J-3937D01*
G01Y189764D02*
Y210237D01*
G01X138190Y185827D02*
G03X142127Y189764I0J3937D01*
G01X180905Y206300D02*
G03Y214174I0J3937D01*
G01X156102Y174016D02*
G03X160039Y177953I0J3937D01*
G01Y202363D02*
Y177953D01*
G01X163976Y206300D02*
G03X160039Y202363I0J-3937D01*
G01X223031Y206300D02*
X163976D01*
G01X156102Y308662D02*
G03X160039Y312599I0J3937D01*
G01X146064Y348820D02*
X230906D01*
G01X146064D02*
G03X142127Y344883I0J-3937D01*
G01Y324410D02*
Y344883D01*
G01X138190Y320473D02*
G03X142127Y324410I0J3937D01*
G01X180905Y340946D02*
G03Y348820I0J3937D01*
G01X160039Y337009D02*
Y312599D01*
G01X163976Y340946D02*
G03X160039Y337009I0J-3937D01*
G01X223031Y340946D02*
X163976D01*
G01X156102Y443308D02*
G03X160039Y447245I0J3937D01*
G01Y471655D02*
Y447245D01*
G01X146064Y483466D02*
X230906D01*
G01X146064D02*
G03X142127Y479529I0J-3937D01*
G01Y459056D02*
Y479529D01*
G01X138190Y455120D02*
G03X142127Y459057I0J3937D01*
G01X180905Y475592D02*
G03Y483466I0J3937D01*
G01X163976Y475592D02*
G03X160039Y471655I0J-3937D01*
G01X223031Y475592D02*
X163976D01*
G01X142127Y593702D02*
Y614175D01*
G01X138190Y589766D02*
G03X142127Y593703I0J3937D01*
G01X156102Y577954D02*
G03X160039Y581891I0J3937D01*
G01Y606301D02*
Y581891D01*
G01X146064Y618112D02*
X230906D01*
G01X146064D02*
G03X142127Y614175I0J-3937D01*
G01X180905Y610238D02*
G03Y618112I0J3937D01*
G01X163976Y610238D02*
G03X160039Y606301I0J-3937D01*
G01X223031Y610238D02*
X163976D01*
G01X142127Y728348D02*
Y748821D01*
G01X138190Y724412D02*
G03X142127Y728349I0J3937D01*
G01X156102Y712600D02*
G03X160039Y716537I0J3937D01*
G01Y740947D02*
Y716537D01*
G01X146064Y752758D02*
X230906D01*
G01X146064D02*
G03X142127Y748821I0J-3937D01*
G01X180905Y744884D02*
G03Y752758I0J3937D01*
G01X163976Y744884D02*
G03X160039Y740947I0J-3937D01*
G01X223031Y744884D02*
X163976D01*
G01X142127Y862994D02*
Y883467D01*
G01X138190Y859058D02*
G03X142127Y862995I0J3937D01*
G01X180905Y879530D02*
G03Y887404I0J3937D01*
G01X156102Y847246D02*
G03X160039Y851183I0J3937D01*
G01Y875593D02*
Y851183D01*
G01X163976Y879530D02*
G03X160039Y875593I0J-3937D01*
G01X223031Y879530D02*
X163976D01*
G01X146064Y887404D02*
X230906D01*
G01X146064D02*
G03X142127Y883467I0J-3937D01*
G01X206102Y79528D02*
G03Y71654I0J-3937D01*
G01X226969Y67717D02*
G03X223031Y71654I-3937J0D01*
G01X226969Y43307D02*
Y67717D01*
G01Y43307D02*
G03X230906Y39370I3937J0D01*
G01X282283D02*
X230906D01*
G01X234843Y75591D02*
G03X230906Y79528I-3937J0D01*
G01X196309Y122835D02*
G03Y130709I0J3937D01*
G01X221506D02*
G03Y122835I0J-3937D01*
G01X234843Y210237D02*
G03X230906Y214174I-3937J0D01*
G01X206102D02*
G03Y206300I0J-3937D01*
G01X226969Y202363D02*
G03X223031Y206300I-3937J0D01*
G01X226969Y177953D02*
Y202363D01*
G01Y177953D02*
G03X230906Y174016I3937J0D01*
G01X282283D02*
X230906D01*
G01X196309Y257481D02*
G03Y265355I0J3937D01*
G01X221506D02*
G03Y257481I0J-3937D01*
G01X226969Y312599D02*
G03X230906Y308662I3937J0D01*
G01X282283D02*
X230906D01*
G01X234843Y344883D02*
G03X230906Y348820I-3937J0D01*
G01X206102D02*
G03Y340946I0J-3937D01*
G01X226969Y337009D02*
G03X223031Y340946I-3937J0D01*
G01X226969Y312599D02*
Y337009D01*
G01X196309Y392127D02*
G03Y400001I0J3937D01*
G01X221506D02*
G03Y392127I0J-3937D01*
G01X226969Y447245D02*
Y471655D01*
G01Y447245D02*
G03X230906Y443308I3937J0D01*
G01X282283D02*
X230906D01*
G01X234843Y479529D02*
G03X230906Y483466I-3937J0D01*
G01X206102D02*
G03Y475592I0J-3937D01*
G01X226969Y471655D02*
G03X223031Y475592I-3937J0D01*
G01X196309Y526773D02*
G03Y534647I0J3937D01*
G01X221506D02*
G03Y526773I0J-3937D01*
G01X226969Y581891D02*
Y606301D01*
G01Y581891D02*
G03X230906Y577954I3937J0D01*
G01X282283D02*
X230906D01*
G01X234843Y614175D02*
G03X230906Y618112I-3937J0D01*
G01X206102D02*
G03Y610238I0J-3937D01*
G01X226969Y606301D02*
G03X223031Y610238I-3937J0D01*
G01X196309Y661419D02*
G03Y669293I0J3937D01*
G01X221506D02*
G03Y661419I0J-3937D01*
G01X226969Y716537D02*
Y740947D01*
G01Y716537D02*
G03X230906Y712600I3937J0D01*
G01X282283D02*
X230906D01*
G01X234843Y748821D02*
G03X230906Y752758I-3937J0D01*
G01X206102D02*
G03Y744884I0J-3937D01*
G01X226969Y740947D02*
G03X223031Y744884I-3937J0D01*
G01X196309Y796065D02*
G03Y803939I0J3937D01*
G01X221506D02*
G03Y796065I0J-3937D01*
G01X206102Y887404D02*
G03Y879530I0J-3937D01*
G01X226969Y875593D02*
G03X223031Y879530I-3937J0D01*
G01X226969Y851183D02*
Y875593D01*
G01Y851183D02*
G03X230906Y847246I3937J0D01*
G01X282283D02*
X230906D01*
G01X234843Y883467D02*
G03X230906Y887404I-3937J0D01*
G01X266339Y55118D02*
Y75591D01*
G01X262402Y51181D02*
G03X266339Y55118I0J3937D01*
G01X238780Y51181D02*
X262402D01*
G01X234843Y55118D02*
G03X238780Y51181I3937J0D01*
G01X234843Y75591D02*
Y55118D01*
G01X270276Y79528D02*
X355119D01*
G01X270276D02*
G03X266339Y75591I0J-3937D01*
G01X270276Y214174D02*
X355119D01*
G01X270276D02*
G03X266339Y210237I0J-3937D01*
G01Y189764D02*
Y210237D01*
G01X262402Y185827D02*
G03X266339Y189764I0J3937D01*
G01X238780Y185827D02*
X262402D01*
G01X234843Y189764D02*
G03X238780Y185827I3937J0D01*
G01X234843Y210237D02*
Y189764D01*
G01X270276Y348820D02*
X355119D01*
G01X270276D02*
G03X266339Y344883I0J-3937D01*
G01Y324410D02*
Y344883D01*
G01X262402Y320473D02*
G03X266339Y324410I0J3937D01*
G01X238780Y320473D02*
X262402D01*
G01X234843Y324410D02*
G03X238780Y320473I3937J0D01*
G01X234843Y344883D02*
Y324410D01*
G01X270276Y483466D02*
X355119D01*
G01X270276D02*
G03X266339Y479529I0J-3937D01*
G01Y459056D02*
Y479529D01*
G01X262402Y455119D02*
G03X266339Y459056I0J3937D01*
G01X238780Y455119D02*
X262402D01*
G01X234843Y459057D02*
G03X238780Y455120I3937J0D01*
G01X234843Y479529D02*
Y459056D01*
G01X266339Y593702D02*
Y614175D01*
G01X262402Y589765D02*
G03X266339Y593702I0J3937D01*
G01X238780Y589765D02*
X262402D01*
G01X234843Y593703D02*
G03X238780Y589766I3937J0D01*
G01X234843Y614175D02*
Y593702D01*
G01X270276Y618112D02*
X355119D01*
G01X270276D02*
G03X266339Y614175I0J-3937D01*
G01Y728348D02*
Y748821D01*
G01X262402Y724411D02*
G03X266339Y728348I0J3937D01*
G01X238780Y724411D02*
X262402D01*
G01X234843Y728349D02*
G03X238780Y724412I3937J0D01*
G01X234843Y748821D02*
Y728348D01*
G01X270276Y752758D02*
X355119D01*
G01X270276D02*
G03X266339Y748821I0J-3937D01*
G01Y862994D02*
Y883467D01*
G01X262402Y859057D02*
G03X266339Y862994I0J3937D01*
G01X238780Y859057D02*
X262402D01*
G01X234843Y862995D02*
G03X238780Y859058I3937J0D01*
G01X234843Y883467D02*
Y862994D01*
G01X270276Y887404D02*
X355119D01*
G01X270276D02*
G03X266339Y883467I0J-3937D01*
G01X306969Y19685D02*
G03X296969I-5000J0D01*
G01D02*
G03X306969I5000J0D01*
G01X325788Y39370D02*
G03Y47244I0J3937D01*
G01Y71654D02*
G03Y79528I0J3937D01*
G01X325591Y71654D02*
X325788D01*
G01X325591Y47244D02*
Y71654D01*
G01X325788Y47244D02*
X325591D01*
G01X282283Y39370D02*
G03X286220Y43307I0J3937D01*
G01Y63780D02*
Y43307D01*
G01X290157Y67717D02*
G03X286220Y63780I0J-3937D01*
G01X313780Y67717D02*
X290157D01*
G01X317717Y63780D02*
G03X313780Y67717I-3937J0D01*
G01X317717Y43307D02*
Y63780D01*
G01Y43307D02*
G03X321654Y39370I3937J0D01*
G01X406496D02*
X321654D01*
G01X307265Y99213D02*
G03X317343I5039J0D01*
G01D02*
G03X307265I-5039J0D01*
G01X306969Y154331D02*
G03X296969I-5000J0D01*
G01D02*
G03X306969I5000J0D01*
G01X325788Y174016D02*
G03Y181890I0J3937D01*
G01Y206300D02*
G03Y214174I0J3937D01*
G01X325591Y206300D02*
X325788D01*
G01X325591Y181890D02*
Y206300D01*
G01X325788Y181890D02*
X325591D01*
G01X282283Y174016D02*
G03X286220Y177953I0J3937D01*
G01Y198426D02*
Y177953D01*
G01X290157Y202363D02*
G03X286220Y198426I0J-3937D01*
G01X313780Y202363D02*
X290157D01*
G01X317717Y198426D02*
G03X313780Y202363I-3937J0D01*
G01X317717Y177953D02*
Y198426D01*
G01Y177953D02*
G03X321654Y174016I3937J0D01*
G01X406496D02*
X321654D01*
G01X307265Y233859D02*
G03X317343I5039J0D01*
G01D02*
G03X307265I-5039J0D01*
G01X325788Y308662D02*
G03Y316536I0J3937D01*
G01X306969Y288977D02*
G03X296969I-5000J0D01*
G01D02*
G03X306969I5000J0D01*
G01X282283Y308662D02*
G03X286220Y312599I0J3937D01*
G01X317717D02*
G03X321654Y308662I3937J0D01*
G01X406496D02*
X321654D01*
G01X325788Y340946D02*
G03Y348820I0J3937D01*
G01X325591Y340946D02*
X325788D01*
G01X325591Y316536D02*
Y340946D01*
G01X325788Y316536D02*
X325591D01*
G01X286220Y333072D02*
Y312599D01*
G01X290157Y337009D02*
G03X286220Y333072I0J-3937D01*
G01X313780Y337009D02*
X290157D01*
G01X317717Y333072D02*
G03X313780Y337009I-3937J0D01*
G01X317717Y312599D02*
Y333072D01*
G01X307265Y368505D02*
G03X317343I5039J0D01*
G01D02*
G03X307265I-5039J0D01*
G01X325788Y443308D02*
G03Y451182I0J3937D01*
G01X325591D02*
Y475592D01*
G01X325788Y451182D02*
X325591D01*
G01X306969Y423623D02*
G03X296969I-5000J0D01*
G01D02*
G03X306969I5000J0D01*
G01X282283Y443308D02*
G03X286220Y447245I0J3937D01*
G01Y467718D02*
Y447245D01*
G01X317717D02*
Y467718D01*
G01Y447245D02*
G03X321654Y443308I3937J0D01*
G01X406496D02*
X321654D01*
G01X307265Y503151D02*
G03X317343I5039J0D01*
G01X325788Y475592D02*
G03Y483466I0J3937D01*
G01X325591Y475592D02*
X325788D01*
G01X290157Y471655D02*
G03X286220Y467718I0J-3937D01*
G01X313780Y471655D02*
X290157D01*
G01X317717Y467718D02*
G03X313780Y471655I-3937J0D01*
G01X317343Y503151D02*
G03X307265I-5039J0D01*
G01X325788Y577954D02*
G03Y585828I0J3937D01*
G01X325591D02*
Y610238D01*
G01X325788Y585828D02*
X325591D01*
G01X306969Y558269D02*
G03X296969I-5000J0D01*
G01D02*
G03X306969I5000J0D01*
G01X282283Y577954D02*
G03X286220Y581891I0J3937D01*
G01Y602364D02*
Y581891D01*
G01X317717D02*
Y602364D01*
G01Y581891D02*
G03X321654Y577954I3937J0D01*
G01X406496D02*
X321654D01*
G01X307265Y637797D02*
G03X317343I5039J0D01*
G01D02*
G03X307265I-5039J0D01*
G01X325788Y610238D02*
G03Y618112I0J3937D01*
G01X325591Y610238D02*
X325788D01*
G01X290157Y606301D02*
G03X286220Y602364I0J-3937D01*
G01X313780Y606301D02*
X290157D01*
G01X317717Y602364D02*
G03X313780Y606301I-3937J0D01*
G01X296969Y692915D02*
G03X306969I5000J0D01*
G01X325788Y712600D02*
G03Y720474I0J3937D01*
G01X325591D02*
Y744884D01*
G01X325788Y720474D02*
X325591D01*
G01X306969Y692915D02*
G03X296969I-5000J0D01*
G01X282283Y712600D02*
G03X286220Y716537I0J3937D01*
G01Y737010D02*
Y716537D01*
G01X290157Y740947D02*
G03X286220Y737010I0J-3937D01*
G01X317717Y737011D02*
G03X313780Y740947I-3937J-1D01*
G01X317717Y716537D02*
Y737010D01*
G01Y716537D02*
G03X321654Y712600I3937J0D01*
G01X406496D02*
X321654D01*
G01X307265Y772443D02*
G03X317343I5039J0D01*
G01D02*
G03X307265I-5039J0D01*
G01X325788Y744884D02*
G03Y752758I0J3937D01*
G01X325591Y744884D02*
X325788D01*
G01X313780Y740947D02*
X290157D01*
G01X306969Y827561D02*
G03X296969I-5000J0D01*
G01D02*
G03X306969I5000J0D01*
G01X325788Y847246D02*
G03Y855120I0J3937D01*
G01Y879530D02*
G03Y887404I0J3937D01*
G01X325591Y879530D02*
X325788D01*
G01X325591Y855120D02*
Y879530D01*
G01X325788Y855120D02*
X325591D01*
G01X282283Y847246D02*
G03X286220Y851183I0J3937D01*
G01Y871656D02*
Y851183D01*
G01X290157Y875593D02*
G03X286220Y871656I0J-3937D01*
G01X313780Y875593D02*
X290157D01*
G01X317717Y871657D02*
G03X313780Y875593I-3937J-1D01*
G01X317717Y851183D02*
Y871656D01*
G01Y851183D02*
G03X321654Y847246I3937J0D01*
G01X406496D02*
X321654D01*
G01X307265Y907089D02*
G03X317343I5039J0D01*
G01D02*
G03X307265I-5039J0D01*
G01X362993Y51181D02*
X386615D01*
G01X359056Y55118D02*
G03X362993Y51181I3937J0D01*
G01X359056Y75591D02*
Y55118D01*
G01X350985Y71654D02*
X351182D01*
G01X350985Y47244D02*
X351182D01*
G01X350985D02*
G03Y39370I0J-3937D01*
G01Y79528D02*
G03Y71654I0J-3937D01*
G01X351182D02*
Y47244D01*
G01X359056Y75591D02*
G03X355119Y79528I-3937J0D01*
G01X362993Y185827D02*
X386615D01*
G01X359056Y189764D02*
G03X362993Y185827I3937J0D01*
G01X359056Y210237D02*
Y189764D01*
G01Y210237D02*
G03X355119Y214174I-3937J0D01*
G01X350985Y206300D02*
X351182D01*
G01X350985Y181890D02*
X351182D01*
G01X350985D02*
G03Y174016I0J-3937D01*
G01Y214174D02*
G03Y206300I0J-3937D01*
G01X351182D02*
Y181890D01*
G01X350985Y316536D02*
G03Y308662I0J-3937D01*
G01X362993Y320473D02*
X386615D01*
G01X359056Y324410D02*
G03X362993Y320473I3937J0D01*
G01X359056Y344883D02*
Y324410D01*
G01Y344883D02*
G03X355119Y348820I-3937J0D01*
G01X350985Y340946D02*
X351182D01*
G01X350985Y316536D02*
X351182D01*
G01X350985Y348820D02*
G03Y340946I0J-3937D01*
G01X351182D02*
Y316536D01*
G01X350985Y451182D02*
X351182D01*
G01X350985D02*
G03Y443308I0J-3937D01*
G01X351182Y475592D02*
Y451182D01*
G01X362993Y455119D02*
X386615D01*
G01X359056Y459056D02*
G03X362993Y455119I3937J0D01*
G01X359056Y479529D02*
Y459056D01*
G01Y479529D02*
G03X355119Y483466I-3937J0D01*
G01X350985Y475592D02*
X351182D01*
G01X350985Y483466D02*
G03Y475592I0J-3937D01*
G01X362993Y589765D02*
X386615D01*
G01X359056Y593702D02*
G03X362993Y589765I3937J0D01*
G01X359056Y614175D02*
Y593702D01*
G01X350985Y585828D02*
X351182D01*
G01X350985D02*
G03Y577954I0J-3937D01*
G01X351182Y610238D02*
Y585828D01*
G01X359056Y614175D02*
G03X355119Y618112I-3937J0D01*
G01X350985Y610238D02*
X351182D01*
G01X350985Y618112D02*
G03Y610238I0J-3937D01*
G01X362993Y724411D02*
X386615D01*
G01X359056Y728349D02*
G03X362993Y724412I3937J0D01*
G01X359056Y748821D02*
Y728348D01*
G01X350985Y720474D02*
X351182D01*
G01X350985D02*
G03Y712600I0J-3937D01*
G01X351182Y744884D02*
Y720474D01*
G01X359056Y748821D02*
G03X355119Y752758I-3937J0D01*
G01X350985Y744884D02*
X351182D01*
G01X350985Y752758D02*
G03Y744884I0J-3937D01*
G01X362993Y859057D02*
X386615D01*
G01X359056Y862995D02*
G03X362993Y859058I3937J0D01*
G01X359056Y883467D02*
Y862994D01*
G01X350985Y879530D02*
X351182D01*
G01X350985Y855120D02*
X351182D01*
G01X350985D02*
G03Y847246I0J-3937D01*
G01Y887404D02*
G03Y879530I0J-3937D01*
G01X351182D02*
Y855120D01*
G01X359056Y883467D02*
G03X355119Y887404I-3937J0D01*
G01X390552Y55118D02*
Y75591D01*
G01X386615Y51181D02*
G03X390552Y55118I0J3937D01*
G01X406496Y39370D02*
G03X410433Y43307I0J3937D01*
G01Y63780D02*
Y43307D01*
G01X414370Y67717D02*
G03X410433Y63780I0J-3937D01*
G01X437992Y67717D02*
X414370D01*
G01X394489Y79528D02*
X479331D01*
G01X394489D02*
G03X390552Y75591I0J-3937D01*
G01X387894Y122835D02*
G03Y130709I0J3937D01*
G01X413091D02*
G03Y122835I0J-3937D01*
G01X394489Y214174D02*
X479331D01*
G01X394489D02*
G03X390552Y210237I0J-3937D01*
G01Y189764D02*
Y210237D01*
G01X386615Y185827D02*
G03X390552Y189764I0J3937D01*
G01X406496Y174016D02*
G03X410433Y177953I0J3937D01*
G01Y198426D02*
Y177953D01*
G01X414370Y202363D02*
G03X410433Y198426I0J-3937D01*
G01X437992Y202363D02*
X414370D01*
G01X387894Y257481D02*
G03Y265355I0J3937D01*
G01X413091D02*
G03Y257481I0J-3937D01*
G01X406496Y308662D02*
G03X410433Y312599I0J3937D01*
G01X394489Y348820D02*
X479331D01*
G01X394489D02*
G03X390552Y344883I0J-3937D01*
G01Y324410D02*
Y344883D01*
G01X386615Y320473D02*
G03X390552Y324410I0J3937D01*
G01X410433Y333072D02*
Y312599D01*
G01X414370Y337009D02*
G03X410433Y333072I0J-3937D01*
G01X437992Y337009D02*
X414370D01*
G01X387894Y392127D02*
G03Y400001I0J3937D01*
G01X413091D02*
G03Y392127I0J-3937D01*
G01X406496Y443308D02*
G03X410433Y447245I0J3937D01*
G01Y467718D02*
Y447245D01*
G01X394489Y483466D02*
X479331D01*
G01X394489D02*
G03X390552Y479529I0J-3937D01*
G01Y459056D02*
Y479529D01*
G01X386615Y455119D02*
G03X390552Y459056I0J3937D01*
G01X414370Y471655D02*
G03X410433Y467718I0J-3937D01*
G01X437992Y471655D02*
X414370D01*
G01X387894Y526773D02*
G03Y534647I0J3937D01*
G01X413091D02*
G03Y526773I0J-3937D01*
G01X390552Y593702D02*
Y614175D01*
G01X386615Y589765D02*
G03X390552Y593702I0J3937D01*
G01X406496Y577954D02*
G03X410433Y581891I0J3937D01*
G01Y602364D02*
Y581891D01*
G01X394489Y618112D02*
X479331D01*
G01X394489D02*
G03X390552Y614175I0J-3937D01*
G01X414370Y606301D02*
G03X410433Y602364I0J-3937D01*
G01X437992Y606301D02*
X414370D01*
G01X387894Y661419D02*
G03Y669293I0J3937D01*
G01X413091D02*
G03Y661419I0J-3937D01*
G01X390552Y728348D02*
Y748821D01*
G01X386615Y724412D02*
G03X390552Y728349I0J3937D01*
G01X406496Y712600D02*
G03X410433Y716537I0J3937D01*
G01Y737010D02*
Y716537D01*
G01X414370Y740947D02*
G03X410433Y737010I0J-3937D01*
G01X394489Y752758D02*
X479331D01*
G01X394489D02*
G03X390552Y748821I0J-3937D01*
G01X437992Y740947D02*
X414370D01*
G01X387894Y796065D02*
G03Y803939I0J3937D01*
G01X413091D02*
G03Y796065I0J-3937D01*
G01X390552Y862994D02*
Y883467D01*
G01X386615Y859058D02*
G03X390552Y862995I0J3937D01*
G01X406496Y847246D02*
G03X410433Y851183I0J3937D01*
G01Y871656D02*
Y851183D01*
G01X414370Y875593D02*
G03X410433Y871656I0J-3937D01*
G01X437992Y875593D02*
X414370D01*
G01X394489Y887404D02*
X479331D01*
G01X394489D02*
G03X390552Y883467I0J-3937D01*
G01X450000Y47244D02*
X449803D01*
G01X450000Y71654D02*
X449803D01*
G01X450000D02*
G03Y79528I0J3937D01*
G01Y39370D02*
G03Y47244I0J3937D01*
G01X449803D02*
Y71654D01*
G01X441929Y63780D02*
G03X437992Y67717I-3937J0D01*
G01X441929Y43307D02*
Y63780D01*
G01Y43307D02*
G03X445866Y39370I3937J0D01*
G01X530709D02*
X445866D01*
G01X450000Y181890D02*
X449803D01*
G01X450000Y206300D02*
X449803D01*
G01X450000D02*
G03Y214174I0J3937D01*
G01Y174016D02*
G03Y181890I0J3937D01*
G01X449803D02*
Y206300D01*
G01X441929Y198426D02*
G03X437992Y202363I-3937J0D01*
G01X441929Y177953D02*
Y198426D01*
G01Y177953D02*
G03X445866Y174016I3937J0D01*
G01X530709D02*
X445866D01*
G01X450000Y308662D02*
G03Y316536I0J3937D01*
G01X441929Y312599D02*
G03X445866Y308662I3937J0D01*
G01X530709D02*
X445866D01*
G01X450000Y316536D02*
X449803D01*
G01X450000Y340946D02*
X449803D01*
G01X450000D02*
G03Y348820I0J3937D01*
G01X449803Y316536D02*
Y340946D01*
G01X441929Y333072D02*
G03X437992Y337009I-3937J0D01*
G01X441929Y312599D02*
Y333072D01*
G01X450000Y451182D02*
X449803D01*
G01X450000Y443308D02*
G03Y451182I0J3937D01*
G01X449803D02*
Y475592D01*
G01X441929Y447245D02*
Y467718D01*
G01Y447245D02*
G03X445866Y443308I3937J0D01*
G01X530709D02*
X445866D01*
G01X450000Y475592D02*
X449803D01*
G01X450000D02*
G03Y483466I0J3937D01*
G01X441929Y467718D02*
G03X437992Y471655I-3937J0D01*
G01X450000Y585828D02*
X449803D01*
G01X450000Y577954D02*
G03Y585828I0J3937D01*
G01X449803D02*
Y610238D01*
G01X441929Y581891D02*
Y602364D01*
G01Y581891D02*
G03X445866Y577954I3937J0D01*
G01X530709D02*
X445866D01*
G01X450000Y610238D02*
X449803D01*
G01X450000D02*
G03Y618112I0J3937D01*
G01X441929Y602364D02*
G03X437992Y606301I-3937J0D01*
G01X450000Y720474D02*
X449803D01*
G01X450000Y712600D02*
G03Y720474I0J3937D01*
G01X449803D02*
Y744884D01*
G01X441929Y737010D02*
G03X437992Y740947I-3937J0D01*
G01X441929Y716537D02*
Y737010D01*
G01Y716537D02*
G03X445866Y712600I3937J0D01*
G01X530709D02*
X445866D01*
G01X450000Y744884D02*
X449803D01*
G01X450000D02*
G03Y752758I0J3937D01*
G01Y855120D02*
X449803D01*
G01X450000Y879530D02*
X449803D01*
G01X450000D02*
G03Y887404I0J3937D01*
G01Y847246D02*
G03Y855120I0J3937D01*
G01X449803D02*
Y879530D01*
G01X441929Y871656D02*
G03X437992Y875593I-3937J0D01*
G01X441929Y851183D02*
Y871656D01*
G01Y851183D02*
G03X445866Y847246I3937J0D01*
G01X530709D02*
X445866D01*
G01X493720Y19685D02*
G03X483642I-5039J0D01*
G01D02*
G03X493720I5039J0D01*
G01X514765Y55118D02*
Y75591D01*
G01X510828Y51181D02*
G03X514765Y55118I0J3937D01*
G01X487205Y51181D02*
X510828D01*
G01X483269Y55118D02*
G03X487205Y51182I3937J1D01*
G01X483268Y75591D02*
Y55118D01*
G01X475197Y79528D02*
G03Y71654I0J-3937D01*
G01Y47244D02*
G03Y39370I0J-3937D01*
G01X475394Y47244D02*
X475197D01*
G01X475394Y71654D02*
Y47244D01*
G01X475197Y71654D02*
X475394D01*
G01X494017Y99213D02*
G03X504017I5000J0D01*
G01D02*
G03X494017I-5000J0D01*
G01X518702Y79528D02*
X570079D01*
G01X518702D02*
G03X514765Y75591I0J-3937D01*
G01X483268D02*
G03X479331Y79528I-3937J0D01*
G01X493720Y154331D02*
G03X483642I-5039J0D01*
G01D02*
G03X493720I5039J0D01*
G01X518702Y214174D02*
X570079D01*
G01X518702D02*
G03X514765Y210237I0J-3937D01*
G01Y189764D02*
Y210237D01*
G01X510828Y185827D02*
G03X514765Y189764I0J3937D01*
G01X487205Y185827D02*
X510828D01*
G01X483269Y189764D02*
G03X487205Y185828I3937J1D01*
G01X483268Y210237D02*
Y189764D01*
G01Y210237D02*
G03X479331Y214174I-3937J0D01*
G01X475197D02*
G03Y206300I0J-3937D01*
G01Y181890D02*
G03Y174016I0J-3937D01*
G01X475394Y181890D02*
X475197D01*
G01X475394Y206300D02*
Y181890D01*
G01X475197Y206300D02*
X475394D01*
G01X494017Y233859D02*
G03X504017I5000J0D01*
G01D02*
G03X494017I-5000J0D01*
G01X475197Y316536D02*
G03Y308662I0J-3937D01*
G01X493720Y288977D02*
G03X483642I-5039J0D01*
G01D02*
G03X493720I5039J0D01*
G01X518702Y348820D02*
X570079D01*
G01X518702D02*
G03X514765Y344883I0J-3937D01*
G01Y324410D02*
Y344883D01*
G01X510828Y320473D02*
G03X514765Y324410I0J3937D01*
G01X487205Y320473D02*
X510828D01*
G01X483269Y324410D02*
G03X487205Y320474I3937J1D01*
G01X483268Y344883D02*
Y324410D01*
G01Y344883D02*
G03X479331Y348820I-3937J0D01*
G01X475197D02*
G03Y340946I0J-3937D01*
G01X475394Y316536D02*
X475197D01*
G01X475394Y340946D02*
Y316536D01*
G01X475197Y340946D02*
X475394D01*
G01X494017Y368505D02*
G03X504017I5000J0D01*
G01D02*
G03X494017I-5000J0D01*
G01X475197Y451182D02*
G03Y443308I0J-3937D01*
G01X475394Y451182D02*
X475197D01*
G01X475394Y475592D02*
Y451182D01*
G01X493720Y423623D02*
G03X483642I-5039J0D01*
G01D02*
G03X493720I5039J0D01*
G01X494017Y503151D02*
G03X504017I5000J0D01*
G01X518702Y483466D02*
X570079D01*
G01X518702D02*
G03X514765Y479529I0J-3937D01*
G01Y459056D02*
Y479529D01*
G01X510828Y455120D02*
G03X514765Y459057I0J3937D01*
G01X487205Y455119D02*
X510828D01*
G01X483269Y459056D02*
G03X487205Y455120I3937J1D01*
G01X483268Y479529D02*
Y459056D01*
G01Y479529D02*
G03X479331Y483466I-3937J0D01*
G01X475197D02*
G03Y475592I0J-3937D01*
G01D02*
X475394D01*
G01X504017Y503151D02*
G03X494017I-5000J0D01*
G01X514765Y593702D02*
Y614175D01*
G01X510828Y589766D02*
G03X514765Y593703I0J3937D01*
G01X487205Y589765D02*
X510828D01*
G01X483269Y593702D02*
G03X487205Y589766I3937J1D01*
G01X483268Y614175D02*
Y593702D01*
G01X475197Y585828D02*
G03Y577954I0J-3937D01*
G01X475394Y585828D02*
X475197D01*
G01X475394Y610238D02*
Y585828D01*
G01X493720Y558269D02*
G03X483642I-5039J0D01*
G01D02*
G03X493720I5039J0D01*
G01X494017Y637797D02*
G03X504017I5000J0D01*
G01D02*
G03X494017I-5000J0D01*
G01X518702Y618112D02*
X570079D01*
G01X518702D02*
G03X514765Y614175I0J-3937D01*
G01X483268D02*
G03X479331Y618112I-3937J0D01*
G01X475197D02*
G03Y610238I0J-3937D01*
G01D02*
X475394D01*
G01X483642Y692915D02*
G03X493720I5039J0D01*
G01X514765Y728348D02*
Y748821D01*
G01X510828Y724412D02*
G03X514765Y728349I0J3937D01*
G01X487205Y724411D02*
X510828D01*
G01X483269Y728348D02*
G03X487205Y724412I3937J1D01*
G01X483268Y748821D02*
Y728348D01*
G01X475197Y720474D02*
G03Y712600I0J-3937D01*
G01X475394Y720474D02*
X475197D01*
G01X475394Y744884D02*
Y720474D01*
G01X493720Y692915D02*
G03X483642I-5039J0D01*
G01X494017Y772443D02*
G03X504017I5000J0D01*
G01D02*
G03X494017I-5000J0D01*
G01X518702Y752758D02*
X570079D01*
G01X518702D02*
G03X514765Y748821I0J-3937D01*
G01X483268D02*
G03X479331Y752758I-3937J0D01*
G01X475197D02*
G03Y744884I0J-3937D01*
G01D02*
X475394D01*
G01X493720Y827561D02*
G03X483642I-5039J0D01*
G01D02*
G03X493720I5039J0D01*
G01X514765Y862994D02*
Y883467D01*
G01X510828Y859058D02*
G03X514765Y862995I0J3937D01*
G01X487205Y859057D02*
X510828D01*
G01X483269Y862994D02*
G03X487205Y859058I3937J1D01*
G01X483268Y883467D02*
Y862994D01*
G01X475197Y887404D02*
G03Y879530I0J-3937D01*
G01Y855120D02*
G03Y847246I0J-3937D01*
G01X475394Y855120D02*
X475197D01*
G01X475394Y879530D02*
Y855120D01*
G01X475197Y879530D02*
X475394D01*
G01X494017Y907089D02*
G03X504017I5000J0D01*
G01D02*
G03X494017I-5000J0D01*
G01X518702Y887404D02*
X570079D01*
G01X518702D02*
G03X514765Y883467I0J-3937D01*
G01X483268D02*
G03X479331Y887404I-3937J0D01*
G01X530709Y39370D02*
G03X534646Y43307I0J3937D01*
G01Y63780D02*
Y43307D01*
G01X538583Y67717D02*
G03X534646Y63780I0J-3937D01*
G01X562205Y67717D02*
X538583D01*
G01X566142Y63780D02*
G03X562205Y67717I-3937J0D01*
G01X566142Y43307D02*
Y63780D01*
G01Y43307D02*
G03X570079Y39370I3937J0D01*
G01X530709Y174016D02*
G03X534646Y177953I0J3937D01*
G01Y198426D02*
Y177953D01*
G01X538583Y202363D02*
G03X534646Y198426I0J-3937D01*
G01X562205Y202363D02*
X538583D01*
G01X566142Y198426D02*
G03X562205Y202363I-3937J0D01*
G01X566142Y177953D02*
Y198426D01*
G01Y177953D02*
G03X570079Y174016I3937J0D01*
G01X530709Y308662D02*
G03X534646Y312599I0J3937D01*
G01Y333072D02*
Y312599D01*
G01X538583Y337009D02*
G03X534646Y333072I0J-3937D01*
G01X562205Y337009D02*
X538583D01*
G01X566142Y333072D02*
G03X562205Y337009I-3937J0D01*
G01X566142Y312599D02*
Y333072D01*
G01Y312599D02*
G03X570079Y308662I3937J0D01*
G01X530709Y443308D02*
G03X534646Y447245I0J3937D01*
G01Y467718D02*
Y447245D01*
G01X566142D02*
Y467718D01*
G01Y447245D02*
G03X570079Y443308I3937J0D01*
G01X538583Y471655D02*
G03X534646Y467718I0J-3937D01*
G01X562205Y471655D02*
X538583D01*
G01X566142Y467718D02*
G03X562205Y471655I-3937J0D01*
G01X530709Y577954D02*
G03X534646Y581891I0J3937D01*
G01Y602364D02*
Y581891D01*
G01X566142D02*
Y602364D01*
G01Y581891D02*
G03X570079Y577954I3937J0D01*
G01X538583Y606301D02*
G03X534646Y602364I0J-3937D01*
G01X562205Y606301D02*
X538583D01*
G01X566142Y602364D02*
G03X562205Y606301I-3937J0D01*
G01X530709Y712601D02*
G03X534646Y716538I0J3937D01*
G01Y737010D02*
Y716537D01*
G01X538583Y740947D02*
G03X534646Y737010I0J-3937D01*
G01X566142D02*
G03X562205Y740947I-3937J0D01*
G01X566142Y716537D02*
Y737010D01*
G01Y716537D02*
G03X570079Y712600I3937J0D01*
G01X562205Y740947D02*
X538583D01*
G01X530709Y847247D02*
G03X534646Y851184I0J3937D01*
G01Y871656D02*
Y851183D01*
G01X538583Y875593D02*
G03X534646Y871656I0J-3937D01*
G01X562205Y875593D02*
X538583D01*
G01X566142Y871656D02*
G03X562205Y875593I-3937J0D01*
G01X566142Y851183D02*
Y871656D01*
G01Y851183D02*
G03X570079Y847246I3937J0D01*
G01X577954Y47244D02*
X637009D01*
G01X574016Y51181D02*
G03X577954Y47244I3937J0D01*
G01X574016Y75591D02*
Y51181D01*
G01X594883Y39370D02*
G03Y47244I0J3937D01*
G01X654921Y39370D02*
X570079D01*
G01X574016Y75591D02*
G03X570079Y79528I-3937J0D01*
G01X604676Y130709D02*
G03Y122835I0J-3937D01*
G01X579479D02*
G03Y130709I0J3937D01*
G01X577954Y181890D02*
X637009D01*
G01X574016Y185827D02*
G03X577954Y181890I3937J0D01*
G01X574016Y210237D02*
Y185827D01*
G01Y210237D02*
G03X570079Y214174I-3937J0D01*
G01X594883Y174016D02*
G03Y181890I0J3937D01*
G01X654921Y174016D02*
X570079D01*
G01X604676Y265355D02*
G03Y257481I0J-3937D01*
G01X579479D02*
G03Y265355I0J3937D01*
G01X594883Y308662D02*
G03Y316536I0J3937D01*
G01X654921Y308662D02*
X570079D01*
G01X577954Y316536D02*
X637009D01*
G01X574016Y320473D02*
G03X577954Y316536I3937J0D01*
G01X574016Y344883D02*
Y320473D01*
G01Y344883D02*
G03X570079Y348820I-3937J0D01*
G01X604676Y400001D02*
G03Y392127I0J-3937D01*
G01X579479D02*
G03Y400001I0J3937D01*
G01X577954Y451182D02*
X637009D01*
G01X574016Y455120D02*
G03X577954Y451183I3937J0D01*
G01X594883Y443308D02*
G03Y451182I0J3937D01*
G01X654921Y443308D02*
X570079D01*
G01X574016Y479529D02*
Y455119D01*
G01Y479529D02*
G03X570079Y483466I-3937J0D01*
G01X604676Y534647D02*
G03Y526773I0J-3937D01*
G01X579479D02*
G03Y534647I0J3937D01*
G01X577954Y585828D02*
X637009D01*
G01X574016Y589766D02*
G03X577954Y585829I3937J0D01*
G01X574016Y614175D02*
Y589765D01*
G01X594883Y577954D02*
G03Y585828I0J3937D01*
G01X654921Y577954D02*
X570079D01*
G01X574016Y614175D02*
G03X570079Y618112I-3937J0D01*
G01X604676Y669293D02*
G03Y661419I0J-3937D01*
G01X579479D02*
G03Y669293I0J3937D01*
G01X577954Y720474D02*
X637009D01*
G01X574016Y724412D02*
G03X577954Y720475I3937J0D01*
G01X574016Y748821D02*
Y724411D01*
G01X594883Y712600D02*
G03Y720474I0J3937D01*
G01X654921Y712600D02*
X570079D01*
G01X574016Y748821D02*
G03X570079Y752758I-3937J0D01*
G01X604676Y803939D02*
G03Y796065I0J-3937D01*
G01X579479D02*
G03Y803939I0J3937D01*
G01X577954Y855120D02*
X637009D01*
G01X574016Y859058D02*
G03X577954Y855121I3937J0D01*
G01X574016Y883467D02*
Y859057D01*
G01X594883Y847246D02*
G03Y855120I0J3937D01*
G01X654921Y847246D02*
X570079D01*
G01X574016Y883467D02*
G03X570079Y887404I-3937J0D01*
G01X640946Y51181D02*
Y75591D01*
G01X637009Y47244D02*
G03X640946Y51181I0J3937D01*
G01X620080Y47244D02*
G03Y39370I0J-3937D01*
G01X654921D02*
G03X658858Y43307I0J3937D01*
G01Y63780D02*
Y43307D01*
G01X662795Y67717D02*
G03X658858Y63780I0J-3937D01*
G01X644883Y79528D02*
X727757D01*
G01X644883D02*
G03X640946Y75591I0J-3937D01*
G01X644883Y214174D02*
X727757D01*
G01X644883D02*
G03X640946Y210237I0J-3937D01*
G01Y185827D02*
Y210237D01*
G01X637009Y181890D02*
G03X640946Y185827I0J3937D01*
G01X620080Y181890D02*
G03Y174016I0J-3937D01*
G01X654921D02*
G03X658858Y177953I0J3937D01*
G01Y198426D02*
Y177953D01*
G01X662795Y202363D02*
G03X658858Y198426I0J-3937D01*
G01X620080Y316536D02*
G03Y308662I0J-3937D01*
G01X654921D02*
G03X658858Y312599I0J3937D01*
G01X644883Y348820D02*
X727757D01*
G01X644883D02*
G03X640946Y344883I0J-3937D01*
G01Y320473D02*
Y344883D01*
G01X637009Y316536D02*
G03X640946Y320473I0J3937D01*
G01X658858Y333072D02*
Y312599D01*
G01X662795Y337009D02*
G03X658858Y333072I0J-3937D01*
G01X637009Y451183D02*
G03X640946Y455120I0J3937D01*
G01X620080Y451182D02*
G03Y443308I0J-3937D01*
G01X654921D02*
G03X658858Y447245I0J3937D01*
G01Y467718D02*
Y447245D01*
G01X644883Y483466D02*
X727757D01*
G01X644883D02*
G03X640946Y479529I0J-3937D01*
G01Y455119D02*
Y479529D01*
G01X662795Y471655D02*
G03X658858Y467718I0J-3937D01*
G01X640946Y589765D02*
Y614175D01*
G01X637009Y585829D02*
G03X640946Y589766I0J3937D01*
G01X620080Y585828D02*
G03Y577954I0J-3937D01*
G01X654921D02*
G03X658858Y581891I0J3937D01*
G01Y602364D02*
Y581891D01*
G01X644883Y618112D02*
X727757D01*
G01X644883D02*
G03X640946Y614175I0J-3937D01*
G01X662795Y606301D02*
G03X658858Y602364I0J-3937D01*
G01X640946Y724411D02*
Y748821D01*
G01X637009Y720475D02*
G03X640946Y724412I0J3937D01*
G01X620080Y720474D02*
G03Y712600I0J-3937D01*
G01X654921D02*
G03X658858Y716537I0J3937D01*
G01Y737010D02*
Y716537D01*
G01X662795Y740947D02*
G03X658858Y737010I0J-3937D01*
G01X644883Y752758D02*
X727757D01*
G01X644883D02*
G03X640946Y748821I0J-3937D01*
G01Y859057D02*
Y883467D01*
G01X637009Y855121D02*
G03X640946Y859058I0J3937D01*
G01X620080Y855120D02*
G03Y847246I0J-3937D01*
G01X654921D02*
G03X658858Y851183I0J3937D01*
G01Y871656D02*
Y851183D01*
G01X662795Y875593D02*
G03X658858Y871656I0J-3937D01*
G01X644883Y887404D02*
X727757D01*
G01X644883D02*
G03X640946Y883467I0J-3937D01*
G01X686319Y19685D02*
G03X674902I-5708J0D01*
G01D02*
G03X686319I5708J0D01*
G01X717106D02*
G03X707106I-5000J0D01*
G01D02*
G03X717106I5000J0D01*
G01X701969Y39370D02*
G03Y47244I0J3937D01*
G01Y71654D02*
G03Y79528I0J3937D01*
G01X698228Y71654D02*
X701969D01*
G01X698228Y47244D02*
Y71654D01*
G01X701969Y47244D02*
X698228D01*
G01X686417Y67717D02*
X662795D01*
G01X690354Y63780D02*
G03X686417Y67717I-3937J0D01*
G01X690354Y43307D02*
Y63780D01*
G01Y43307D02*
G03X694291Y39370I3937J0D01*
G01X724409D02*
X694291D01*
G01X686319Y154331D02*
G03X674902I-5708J0D01*
G01D02*
G03X686319I5708J0D01*
G01X717106D02*
G03X707106I-5000J0D01*
G01D02*
G03X717106I5000J0D01*
G01X701969Y174016D02*
G03Y181890I0J3937D01*
G01Y206300D02*
G03Y214174I0J3937D01*
G01X698228Y206300D02*
X701969D01*
G01X698228Y181890D02*
Y206300D01*
G01X701969Y181890D02*
X698228D01*
G01X686417Y202363D02*
X662795D01*
G01X690354Y198426D02*
G03X686417Y202363I-3937J0D01*
G01X690354Y177953D02*
Y198426D01*
G01Y177953D02*
G03X694291Y174016I3937J0D01*
G01X724409D02*
X694291D01*
G01X701969Y308662D02*
G03Y316536I0J3937D01*
G01X686319Y288977D02*
G03X674902I-5708J0D01*
G01D02*
G03X686319I5708J0D01*
G01X717106D02*
G03X707106I-5000J0D01*
G01D02*
G03X717106I5000J0D01*
G01X690354Y312599D02*
G03X694291Y308662I3937J0D01*
G01X724409D02*
X694291D01*
G01X701969Y340946D02*
G03Y348820I0J3937D01*
G01X698228Y340946D02*
X701969D01*
G01X698228Y316536D02*
Y340946D01*
G01X701969Y316536D02*
X698228D01*
G01X686417Y337009D02*
X662795D01*
G01X690354Y333072D02*
G03X686417Y337009I-3937J0D01*
G01X690354Y312599D02*
Y333072D01*
G01X701969Y443308D02*
G03Y451182I0J3937D01*
G01X698228D02*
Y475592D01*
G01X701969Y451182D02*
X698228D01*
G01X686319Y423623D02*
G03X674902I-5708J0D01*
G01D02*
G03X686319I5708J0D01*
G01X717106D02*
G03X707106I-5000J0D01*
G01D02*
G03X717106I5000J0D01*
G01X690354Y447245D02*
Y467718D01*
G01Y447245D02*
G03X694291Y443308I3937J0D01*
G01X724409D02*
X694291D01*
G01X701969Y475592D02*
G03Y483466I0J3937D01*
G01X698228Y475592D02*
X701969D01*
G01X686417Y471655D02*
X662795D01*
G01X690354Y467718D02*
G03X686417Y471655I-3937J0D01*
G01X701969Y577954D02*
G03Y585828I0J3937D01*
G01X698228D02*
Y610238D01*
G01X701969Y585828D02*
X698228D01*
G01X686319Y558269D02*
G03X674902I-5708J0D01*
G01D02*
G03X686319I5708J0D01*
G01X717106D02*
G03X707106I-5000J0D01*
G01D02*
G03X717106I5000J0D01*
G01X690354Y581891D02*
Y602364D01*
G01Y581891D02*
G03X694291Y577954I3937J0D01*
G01X724409D02*
X694291D01*
G01X701969Y610238D02*
G03Y618112I0J3937D01*
G01X698228Y610238D02*
X701969D01*
G01X686417Y606301D02*
X662795D01*
G01X690354Y602364D02*
G03X686417Y606301I-3937J0D01*
G01X674902Y692915D02*
G03X686319I5708J0D01*
G01X707106D02*
G03X717106I5000J0D01*
G01X701969Y712600D02*
G03Y720474I0J3937D01*
G01X698228D02*
Y744884D01*
G01X701969Y720474D02*
X698228D01*
G01X686319Y692915D02*
G03X674902I-5708J0D01*
G01X717106D02*
G03X707106I-5000J0D01*
G01X690354Y737010D02*
G03X686417Y740947I-3937J0D01*
G01X690354Y716537D02*
Y737010D01*
G01Y716538D02*
G03X694291Y712601I3937J0D01*
G01X724409Y712600D02*
X694291D01*
G01X701969Y744884D02*
G03Y752758I0J3937D01*
G01X698228Y744884D02*
X701969D01*
G01X686417Y740947D02*
X662795D01*
G01X686319Y827561D02*
G03X674902I-5708J0D01*
G01D02*
G03X686319I5708J0D01*
G01X717106D02*
G03X707106I-5000J0D01*
G01D02*
G03X717106I5000J0D01*
G01X701969Y847246D02*
G03Y855120I0J3937D01*
G01Y879530D02*
G03Y887404I0J3937D01*
G01X698228Y879530D02*
X701969D01*
G01X698228Y855120D02*
Y879530D01*
G01X701969Y855120D02*
X698228D01*
G01X686417Y875593D02*
X662795D01*
G01X690354Y871656D02*
G03X686417Y875593I-3937J0D01*
G01X690354Y851183D02*
Y871656D01*
G01Y851184D02*
G03X694291Y847247I3937J0D01*
G01X724409Y847246D02*
X694291D01*
G01X736220Y0D02*
G03X740157Y-3937I3937J0D01*
G01X736220Y5118D02*
Y0D01*
G01X740157Y-3937D02*
X793111D01*
G01X736220Y5118D02*
G03X728346I-3937J0D01*
G01X724409Y-3937D02*
G03X728346Y0I0J3937D01*
G01D02*
Y35433D01*
G01X720079Y47244D02*
G03Y39370I0J-3937D01*
G01Y79528D02*
G03Y71654I0J-3937D01*
G01X723820D02*
Y47244D01*
G01X720079Y71654D02*
X723820D01*
G01Y47244D02*
X720079D01*
G01X740157Y43307D02*
G03X736220Y39370I0J-3937D01*
G01X740157Y43307D02*
X759253D01*
G01X736220Y30315D02*
Y39370D01*
G01X735631Y51181D02*
X759253D01*
G01X731694Y55118D02*
G03X735631Y51181I3937J0D01*
G01X731694Y75591D02*
Y55118D01*
G01X728346Y30315D02*
G03X736220I3937J0D01*
G01X728346Y35433D02*
G03X724409Y39370I-3937J0D01*
G01X747540Y99213D02*
G03X758957I5708J0D01*
G01D02*
G03X747540I-5709J0D01*
G01X731694Y75591D02*
G03X727757Y79528I-3937J0D01*
G01X736220Y134646D02*
G03X740157Y130709I3937J0D01*
G01X771064D02*
X740157D01*
G01X736220Y139764D02*
Y134646D01*
G01X728346Y164961D02*
G03X736220I3937J0D01*
G01Y139764D02*
G03X728346I-3937J0D01*
G01X724409Y130709D02*
G03X728346Y134646I0J3937D01*
G01X736220Y164961D02*
Y174016D01*
G01X728346Y134646D02*
Y170079D01*
G01X720079Y181890D02*
G03Y174016I0J-3937D01*
G01Y214174D02*
G03Y206300I0J-3937D01*
G01X723820D02*
Y181890D01*
G01X720079Y206300D02*
X723820D01*
G01Y181890D02*
X720079D01*
G01X740157Y177953D02*
G03X736220Y174016I0J-3937D01*
G01X740157Y177953D02*
X759253D01*
G01X735631Y185827D02*
X759253D01*
G01X731694Y189764D02*
G03X735631Y185827I3937J0D01*
G01X731694Y210237D02*
Y189764D01*
G01Y210237D02*
G03X727757Y214174I-3937J0D01*
G01X728346Y170079D02*
G03X724409Y174016I-3937J0D01*
G01X747540Y233859D02*
G03X758957I5708J0D01*
G01D02*
G03X747540I-5709J0D01*
G01X720079Y316536D02*
G03Y308662I0J-3937D01*
G01X736220Y269292D02*
G03X740157Y265355I3937J0D01*
G01Y312599D02*
G03X736220Y308662I0J-3937D01*
G01X771064Y265355D02*
X740157D01*
G01X736220Y274410D02*
Y269292D01*
G01X728346Y299607D02*
G03X736220I3937J0D01*
G01Y274410D02*
G03X728346I-3937J0D01*
G01X736220Y299607D02*
Y308662D01*
G01X724409Y265355D02*
G03X728346Y269292I0J3937D01*
G01Y304725D02*
G03X724409Y308662I-3937J0D01*
G01X728346Y269292D02*
Y304725D01*
G01X720079Y348820D02*
G03Y340946I0J-3937D01*
G01X723820D02*
Y316536D01*
G01X720079Y340946D02*
X723820D01*
G01Y316536D02*
X720079D01*
G01X740157Y312599D02*
X759253D01*
G01X735631Y320473D02*
X759253D01*
G01X731694Y324410D02*
G03X735631Y320473I3937J0D01*
G01X731694Y344883D02*
Y324410D01*
G01Y344883D02*
G03X727757Y348820I-3937J0D01*
G01X736220Y403938D02*
G03X740157Y400001I3937J0D01*
G01X771064D02*
X740157D01*
G01X736220Y409056D02*
Y403938D01*
G01X724409Y400001D02*
G03X728346Y403938I0J3937D01*
G01D02*
Y439371D01*
G01X747540Y368505D02*
G03X758957I5708J0D01*
G01D02*
G03X747540I-5709J0D01*
G01X720079Y451182D02*
G03Y443308I0J-3937D01*
G01X723820Y475592D02*
Y451182D01*
G01D02*
X720079D01*
G01X740157Y447245D02*
G03X736220Y443308I0J-3937D01*
G01X740157Y447245D02*
X759253D01*
G01X728346Y434253D02*
G03X736220I3937J0D01*
G01Y409056D02*
G03X728346I-3937J0D01*
G01X736220Y434253D02*
Y443308D01*
G01X728346Y439371D02*
G03X724409Y443308I-3937J0D01*
G01X720079Y483466D02*
G03Y475592I0J-3937D01*
G01D02*
X723820D01*
G01X747540Y503151D02*
G03X758957I5708J0D01*
G01X735631Y455119D02*
X759253D01*
G01X731694Y459056D02*
G03X735631Y455119I3937J0D01*
G01X731694Y479529D02*
Y459056D01*
G01Y479529D02*
G03X727757Y483466I-3937J0D01*
G01X736220Y538584D02*
G03X740157Y534647I3937J0D01*
G01X771064D02*
X740157D01*
G01X736220Y543702D02*
Y538584D01*
G01Y543702D02*
G03X728346I-3937J0D01*
G01X724409Y534647D02*
G03X728346Y538584I0J3937D01*
G01D02*
Y574017D01*
G01X758957Y503151D02*
G03X747540I-5709J0D01*
G01X720079Y585828D02*
G03Y577954I0J-3937D01*
G01X723820Y610238D02*
Y585828D01*
G01D02*
X720079D01*
G01X740157Y581891D02*
G03X736220Y577954I0J-3937D01*
G01X740157Y581891D02*
X759253D01*
G01X728346Y568899D02*
G03X736220I3937J0D01*
G01D02*
Y577954D01*
G01X735631Y589765D02*
X759253D01*
G01X731694Y593702D02*
G03X735631Y589765I3937J0D01*
G01X731694Y614175D02*
Y593702D01*
G01X728346Y574017D02*
G03X724409Y577954I-3937J0D01*
G01X720079Y618112D02*
G03Y610238I0J-3937D01*
G01D02*
X723820D01*
G01X747540Y637797D02*
G03X758957I5708J0D01*
G01D02*
G03X747540I-5709J0D01*
G01X731694Y614175D02*
G03X727757Y618112I-3937J0D01*
G01X736220Y673230D02*
G03X740157Y669293I3937J0D01*
G01X771064D02*
X740157D01*
G01X736220Y678348D02*
Y673230D01*
G01Y678348D02*
G03X728346I-3937J0D01*
G01X724409Y669293D02*
G03X728346Y673230I0J3937D01*
G01D02*
Y708663D01*
G01X720079Y720474D02*
G03Y712600I0J-3937D01*
G01X723820Y744884D02*
Y720474D01*
G01D02*
X720079D01*
G01X740157Y716537D02*
G03X736220Y712600I0J-3937D01*
G01X740157Y716537D02*
X759253D01*
G01X728346Y703545D02*
G03X736220I3937J0D01*
G01D02*
Y712600D01*
G01X735631Y724411D02*
X759253D01*
G01X731694Y728348D02*
G03X735631Y724411I3937J0D01*
G01X731694Y748821D02*
Y728348D01*
G01X728346Y708664D02*
G03X724409Y712601I-3937J0D01*
G01X720079Y752758D02*
G03Y744884I0J-3937D01*
G01D02*
X723820D01*
G01X747540Y772443D02*
G03X758957I5708J0D01*
G01D02*
G03X747540I-5709J0D01*
G01X731694Y748821D02*
G03X727757Y752758I-3937J0D01*
G01X736220Y807876D02*
G03X740157Y803939I3937J0D01*
G01X771064D02*
X740157D01*
G01X736220Y812995D02*
Y807876D01*
G01X728346Y838191D02*
G03X736220I3937J0D01*
G01Y812995D02*
G03X728346I-3937J0D01*
G01X724409Y803939D02*
G03X728346Y807876I0J3937D01*
G01D02*
Y843309D01*
G01X720079Y855120D02*
G03Y847246I0J-3937D01*
G01Y887404D02*
G03Y879530I0J-3937D01*
G01X723820D02*
Y855120D01*
G01X720079Y879530D02*
X723820D01*
G01Y855120D02*
X720079D01*
G01X740157Y851183D02*
G03X736220Y847246I0J-3937D01*
G01X740157Y851183D02*
X759253D01*
G01X736220Y838191D02*
Y847246D01*
G01X735631Y859057D02*
X759253D01*
G01X731694Y862994D02*
G03X735631Y859057I3937J0D01*
G01X731694Y883467D02*
Y862994D01*
G01X728346Y843310D02*
G03X724409Y847247I-3937J0D01*
G01X747540Y907089D02*
G03X758957I5708J0D01*
G01D02*
G03X747540I-5709J0D01*
G01X731694Y883467D02*
G03X727757Y887404I-3937J0D01*
G01X793111Y-3937D02*
G03X800985Y3937I0J7874D01*
G01Y67717D02*
Y3937D01*
G01X789036Y19685D02*
G03I-4291J0D01*
G01X800985Y67717D02*
G03X797048Y71654I-3937J0D01*
G01X771064Y55118D02*
Y71654D01*
G01X796261D02*
X797048D01*
G01X759253Y43307D02*
G03X771064Y55118I0J11811D01*
G01X763190D02*
Y75591D01*
G01X759253Y51181D02*
G03X763190Y55118I0J3937D01*
G01X796261Y79528D02*
G03Y71654I0J-3937D01*
G01X771064D02*
G03Y79528I0J3937D01*
G01X779706Y99213D02*
G03X789784I5039J0D01*
G01D02*
G03X779706I-5039J0D01*
G01X800985Y118898D02*
G03X797048Y122835I-3937J0D01*
G01X800985Y83465D02*
Y118898D01*
G01X797048Y79528D02*
G03X800985Y83465I0J3937D01*
G01X767127Y79528D02*
X797048D01*
G01X767127D02*
G03X763190Y75591I0J-3937D01*
G01X797048Y130709D02*
G03X800985Y134646I0J3937D01*
G01X796261Y130709D02*
X797048D01*
G01X800985Y202363D02*
Y134646D01*
G01X789036Y154331D02*
G03I-4291J0D01*
G01X771064Y122835D02*
G03Y130709I0J3937D01*
G01X796261D02*
G03Y122835I0J-3937D01*
G01X800985Y202363D02*
G03X797048Y206300I-3937J0D01*
G01Y214174D02*
G03X800985Y218111I0J3937D01*
G01X796261Y206300D02*
X797048D01*
G01X767127Y214174D02*
X797048D01*
G01X767127D02*
G03X763190Y210237I0J-3937D01*
G01X771064Y189764D02*
Y206300D01*
G01X763190Y189764D02*
Y210237D01*
G01X759253Y177953D02*
G03X771064Y189764I0J11811D01*
G01X759253Y185827D02*
G03X763190Y189764I0J3937D01*
G01X796261Y214174D02*
G03Y206300I0J-3937D01*
G01X771064D02*
G03Y214174I0J3937D01*
G01Y257481D02*
G03Y265355I0J3937D01*
G01X796261D02*
G03Y257481I0J-3937D01*
G01X779706Y233859D02*
G03X789784I5039J0D01*
G01D02*
G03X779706I-5039J0D01*
G01X800985Y253544D02*
G03X797048Y257481I-3937J0D01*
G01X800985Y218111D02*
Y253544D01*
G01X797048Y265355D02*
G03X800985Y269292I0J3937D01*
G01X796261Y265355D02*
X797048D01*
G01X800985Y337009D02*
Y269292D01*
G01X789036Y288977D02*
G03I-4291J0D01*
G01X800985Y337009D02*
G03X797048Y340946I-3937J0D01*
G01X796261D02*
X797048D01*
G01X771064Y324410D02*
Y340946D01*
G01X759253Y312599D02*
G03X771064Y324410I0J11811D01*
G01X796261Y348820D02*
G03Y340946I0J-3937D01*
G01X771064D02*
G03Y348820I0J3937D01*
G01X800985Y352757D02*
Y388190D01*
G01X797048Y348820D02*
G03X800985Y352757I0J3937D01*
G01X767127Y348820D02*
X797048D01*
G01X767127D02*
G03X763190Y344883I0J-3937D01*
G01Y324410D02*
Y344883D01*
G01X759253Y320473D02*
G03X763190Y324410I0J3937D01*
G01X797048Y400001D02*
G03X800985Y403938I0J3937D01*
G01X796261Y400001D02*
X797048D01*
G01X800985Y471655D02*
Y403938D01*
G01X771064Y392127D02*
G03Y400001I0J3937D01*
G01X796261D02*
G03Y392127I0J-3937D01*
G01X779706Y368505D02*
G03X789784I5039J0D01*
G01D02*
G03X779706I-5039J0D01*
G01X800985Y388190D02*
G03X797048Y392127I-3937J0D01*
G01X759253Y447246D02*
G03X771064Y459057I0J11811D01*
G01X789036Y423623D02*
G03I-4291J0D01*
G01X800985Y471655D02*
G03X797048Y475592I-3937J0D01*
G01X796261D02*
X797048D01*
G01X771064Y459056D02*
Y475592D01*
G01X796261Y483466D02*
G03Y475592I0J-3937D01*
G01X771064D02*
G03Y483466I0J3937D01*
G01X779706Y503151D02*
G03X789784I5039J0D01*
G01X800985Y487403D02*
Y522836D01*
G01X797048Y483466D02*
G03X800985Y487403I0J3937D01*
G01X767127Y483466D02*
X797048D01*
G01X767127D02*
G03X763190Y479529I0J-3937D01*
G01Y459056D02*
Y479529D01*
G01X759253Y455120D02*
G03X763190Y459057I0J3937D01*
G01X797048Y534647D02*
G03X800985Y538584I0J3937D01*
G01X796261Y534647D02*
X797048D01*
G01X800985Y606301D02*
Y538584D01*
G01X771064Y526773D02*
G03Y534647I0J3937D01*
G01X796261D02*
G03Y526773I0J-3937D01*
G01X789784Y503151D02*
G03X779706I-5039J0D01*
G01X800985Y522836D02*
G03X797048Y526773I-3937J0D01*
G01X771064Y593702D02*
Y610238D01*
G01X759253Y581892D02*
G03X771064Y593703I0J11811D01*
G01X789036Y558269D02*
G03I-4291J0D01*
G01X763190Y593702D02*
Y614175D01*
G01X759253Y589766D02*
G03X763190Y593703I0J3937D01*
G01X800985Y606301D02*
G03X797048Y610238I-3937J0D01*
G01X796261D02*
X797048D01*
G01X796261Y618112D02*
G03Y610238I0J-3937D01*
G01X771064D02*
G03Y618112I0J3937D01*
G01X779706Y637797D02*
G03X789784I5039J0D01*
G01D02*
G03X779706I-5039J0D01*
G01X800985Y622049D02*
Y657482D01*
G01X797048Y618112D02*
G03X800985Y622049I0J3937D01*
G01X767127Y618112D02*
X797048D01*
G01X767127D02*
G03X763190Y614175I0J-3937D01*
G01X797048Y669293D02*
G03X800985Y673230I0J3937D01*
G01X796261Y669293D02*
X797048D01*
G01X800985Y740947D02*
Y673230D01*
G01X789036Y692915D02*
G03I-4291J0D01*
G01X771064Y661419D02*
G03Y669293I0J3937D01*
G01X796261D02*
G03Y661419I0J-3937D01*
G01X800985Y657482D02*
G03X797048Y661419I-3937J0D01*
G01X771064Y728348D02*
Y744884D01*
G01X759253Y716538D02*
G03X771064Y728349I0J11811D01*
G01X763190Y728348D02*
Y748821D01*
G01X759253Y724412D02*
G03X763190Y728349I0J3937D01*
G01X800985Y740947D02*
G03X797048Y744884I-3937J0D01*
G01X796261D02*
X797048D01*
G01X796261Y752758D02*
G03Y744884I0J-3937D01*
G01X771064D02*
G03Y752758I0J3937D01*
G01X779706Y772443D02*
G03X789784I5039J0D01*
G01D02*
G03X779706I-5039J0D01*
G01X800985Y756695D02*
Y792128D01*
G01X797048Y752758D02*
G03X800985Y756695I0J3937D01*
G01X767127Y752758D02*
X797048D01*
G01X767127D02*
G03X763190Y748821I0J-3937D01*
G01X800985Y855100D02*
Y807876D01*
G01X797048Y803939D02*
G03X800985Y807876I0J3937D01*
G01X796261Y803939D02*
X797048D01*
G01X789036Y827561D02*
G03I-4291J0D01*
G01X771064Y796065D02*
G03Y803939I0J3937D01*
G01X796261D02*
G03Y796065I0J-3937D01*
G01X800985Y792128D02*
G03X797048Y796065I-3937J0D01*
G01X800985Y862974D02*
G03Y855100I0J-3937D01*
G01Y875593D02*
G03X797048Y879530I-3937J0D01*
G01X800985Y875593D02*
Y862974D01*
G01X796261Y879530D02*
X797048D01*
G01X771064Y862994D02*
Y879530D01*
G01X759253Y851184D02*
G03X771064Y862995I0J11811D01*
G01X796261Y887404D02*
G03Y879530I0J-3937D01*
G01X771064D02*
G03Y887404I0J3937D01*
G01X763190Y862994D02*
Y883467D01*
G01X759253Y859058D02*
G03X763190Y862995I0J3937D01*
G01X779706Y907089D02*
G03X789784I5039J0D01*
G01D02*
G03X779706I-5039J0D01*
G01X800985Y926774D02*
G03X797048Y930711I-3937J0D01*
G01X800985Y891341D02*
Y926774D01*
G01X797048Y887404D02*
G03X800985Y891341I0J3937D01*
G01X767127Y887404D02*
X797048D01*
G01X767127D02*
G03X763190Y883467I0J-3937D01*
M02*
